(kicad_pcb
	(version 20241229)
	(generator "pcbnew")
	(generator_version "9.0")
	(general
		(thickness 1.599998)
		(legacy_teardrops no)
	)
	(paper "A4")
	(title_block
		(title "Artix - Datacenter Secure Control Module (DC-SCM)")
		(date "2024-11-06")
		(rev "1.1.3")
		(comment 9 "footprint 110 of 544 (U14), pads 79-157 of 484")
	)
	(layers
		(0 "F.Cu" signal)
		(4 "In1.Cu" signal)
		(6 "In2.Cu" signal)
		(8 "In3.Cu" signal)
		(10 "In4.Cu" signal)
		(12 "In5.Cu" signal)
		(14 "In6.Cu" signal)
		(2 "B.Cu" signal)
		(9 "F.Adhes" user "F.Adhesive")
		(11 "B.Adhes" user "B.Adhesive")
		(13 "F.Paste" user)
		(15 "B.Paste" user)
		(5 "F.SilkS" user "F.Silkscreen")
		(7 "B.SilkS" user "B.Silkscreen")
		(1 "F.Mask" user)
		(3 "B.Mask" user)
		(17 "Dwgs.User" user "User.Drawings")
		(19 "Cmts.User" user "User.Comments")
		(21 "Eco1.User" user "User.Eco1")
		(23 "Eco2.User" user "User.Eco2")
		(25 "Edge.Cuts" user)
		(27 "Margin" user)
		(31 "F.CrtYd" user "F.Courtyard")
		(29 "B.CrtYd" user "B.Courtyard")
		(35 "F.Fab" user)
		(33 "B.Fab" user)
	)
	(footprint "antmicro-footprints:BGA-484_23x23mm_Layout22x22_P1mm_FGG484"
		(layer "F.Cu")
		(at 101.275 119.675 90)
		(property "Reference" "U14"
			(at 11.965 9.405 180)
			(layer "F.SilkS")
			(effects
				(font
					(size 0.7 0.7)
					(thickness 0.15)
				)
				(justify left bottom)
			)
		)
		(property "Value" "XC7A100T-FGG484"
			(at 0 13.1 90)
			(layer "F.Fab")
			(effects
				(font
					(size 0.7 0.7)
					(thickness 0.15)
				)
				(justify left bottom)
			)
		)
		(property "Datasheet" "https://docs.xilinx.com/v/u/en-US/ds181_Artix_7_Data_Sheet"
			(at 0 0 90)
			(layer "F.Fab")
			(hide yes)
			(effects
				(font
					(size 1.27 1.27)
					(thickness 0.15)
				)
			)
		)
		(property "Description" "Artix-7 Field Programmable Gate Array IC 210 324-LFBGA, CSPBGA"
			(at 0 0 90)
			(layer "F.Fab")
			(hide yes)
			(effects
				(font
					(size 1.27 1.27)
					(thickness 0.15)
				)
			)
		)
		(property "Author" "Antmicro"
			(at 220.95 18.4 0)
			(layer "F.Fab")
			(hide yes)
			(effects
				(font
					(size 1 1)
					(thickness 0.15)
				)
			)
		)
		(property "License" "Apache-2.0"
			(at 220.95 18.4 0)
			(layer "F.Fab")
			(hide yes)
			(effects
				(font
					(size 1 1)
					(thickness 0.15)
				)
			)
		)
		(property "MPN" "XC7A100T-FGG484"
			(at 220.95 18.4 0)
			(layer "F.Fab")
			(hide yes)
			(effects
				(font
					(size 1 1)
					(thickness 0.15)
				)
			)
		)
		(property "Manufacturer" "AMD-Xilinx"
			(at 220.95 18.4 0)
			(layer "F.Fab")
			(hide yes)
			(effects
				(font
					(size 1 1)
					(thickness 0.15)
				)
			)
		)
		(sheetname "/FPGA power supply/")
		(sheetfile "fpga-power-supply.kicad_sch")
		(solder_mask_margin 0.05)
		(attr smd)
		(pad "B13" smd circle
			(at 1.499 -9.5 90)
			(size 0.5 0.5)
			(layers "F.Cu" "F.Mask" "F.Paste")
			(net 76 "NCSI_CLK")
			(pinfunction "IO_L8N_T1_16")
			(pintype "bidirectional")
		)
		(pad "B14" smd circle
			(at 2.499 -9.5 90)
			(size 0.5 0.5)
			(layers "F.Cu" "F.Mask" "F.Paste")
			(net 2 "VCC3V3")
			(pinfunction "VCCO_16")
			(pintype "passive")
		)
		(pad "B15" smd circle
			(at 3.499 -9.5 90)
			(size 0.5 0.5)
			(layers "F.Cu" "F.Mask" "F.Paste")
			(net 83 "NCSI_RXD1")
			(pinfunction "IO_L7P_T1_16")
			(pintype "bidirectional")
		)
		(pad "B16" smd circle
			(at 4.498 -9.5 90)
			(size 0.5 0.5)
			(layers "F.Cu" "F.Mask" "F.Paste")
			(net 526 "SPI0_MISO_R")
			(pinfunction "IO_L7N_T1_16")
			(pintype "bidirectional")
		)
		(pad "B17" smd circle
			(at 5.499 -9.5 90)
			(size 0.5 0.5)
			(layers "F.Cu" "F.Mask" "F.Paste")
			(net 554 "unconnected-(U14B-IO_L11P_T1_SRCC_16-PadB17)")
			(pinfunction "IO_L11P_T1_SRCC_16")
			(pintype "bidirectional+no_connect")
		)
		(pad "B18" smd circle
			(at 6.499 -9.5 90)
			(size 0.5 0.5)
			(layers "F.Cu" "F.Mask" "F.Paste")
			(net 555 "unconnected-(U14B-IO_L11N_T1_SRCC_16-PadB18)")
			(pinfunction "IO_L11N_T1_SRCC_16")
			(pintype "bidirectional+no_connect")
		)
		(pad "B19" smd circle
			(at 7.499 -9.5 90)
			(size 0.5 0.5)
			(layers "F.Cu" "F.Mask" "F.Paste")
			(net 1 "GND")
			(pinfunction "GND")
			(pintype "passive")
		)
		(pad "B20" smd circle
			(at 8.499 -9.5 90)
			(size 0.5 0.5)
			(layers "F.Cu" "F.Mask" "F.Paste")
			(net 168 "I3C[0]_SDA_3V3")
			(pinfunction "IO_L16P_T2_16")
			(pintype "bidirectional")
		)
		(pad "B21" smd circle
			(at 9.499 -9.5 90)
			(size 0.5 0.5)
			(layers "F.Cu" "F.Mask" "F.Paste")
			(net 556 "unconnected-(U14B-IO_L21P_T3_DQS_16-PadB21)")
			(pinfunction "IO_L21P_T3_DQS_16")
			(pintype "bidirectional+no_connect")
		)
		(pad "B22" smd circle
			(at 10.499 -9.5 90)
			(size 0.5 0.5)
			(layers "F.Cu" "F.Mask" "F.Paste")
			(net 301 "ROT_RDY\\ROT_GPIO0")
			(pinfunction "IO_L20N_T3_16")
			(pintype "bidirectional")
		)
		(pad "C1" smd circle
			(at -10.5 -8.5 90)
			(size 0.5 0.5)
			(layers "F.Cu" "F.Mask" "F.Paste")
			(net 3 "VCC1V35")
			(pinfunction "VCCO_35")
			(pintype "power_in")
		)
		(pad "C2" smd circle
			(at -9.5 -8.5 90)
			(size 0.5 0.5)
			(layers "F.Cu" "F.Mask" "F.Paste")
			(net 182 "DDR3_DQ12")
			(pinfunction "IO_L2P_T0_AD12P_35")
			(pintype "bidirectional")
		)
		(pad "C3" smd circle
			(at -8.5 -8.5 90)
			(size 0.5 0.5)
			(layers "F.Cu" "F.Mask" "F.Paste")
			(net 1 "GND")
			(pinfunction "GND")
			(pintype "passive")
		)
		(pad "C4" smd circle
			(at -7.5 -8.5 90)
			(size 0.5 0.5)
			(layers "F.Cu" "F.Mask" "F.Paste")
			(net 339 "VCC1V2")
			(pinfunction "MGTAVTT")
			(pintype "passive")
		)
		(pad "C5" smd circle
			(at -6.5 -8.5 90)
			(size 0.5 0.5)
			(layers "F.Cu" "F.Mask" "F.Paste")
			(net 557 "unconnected-(U14E-MGTPTXN1_216-PadC5)")
			(pinfunction "MGTPTXN1_216")
			(pintype "bidirectional+no_connect")
		)
		(pad "C6" smd circle
			(at -5.5 -8.5 90)
			(size 0.5 0.5)
			(layers "F.Cu" "F.Mask" "F.Paste")
			(net 1 "GND")
			(pinfunction "GND")
			(pintype "passive")
		)
		(pad "C7" smd circle
			(at -4.5 -8.5 90)
			(size 0.5 0.5)
			(layers "F.Cu" "F.Mask" "F.Paste")
			(net 558 "unconnected-(U14E-MGTPTXN3_216-PadC7)")
			(pinfunction "MGTPTXN3_216")
			(pintype "bidirectional+no_connect")
		)
		(pad "C8" smd circle
			(at -3.5 -8.5 90)
			(size 0.5 0.5)
			(layers "F.Cu" "F.Mask" "F.Paste")
			(net 339 "VCC1V2")
			(pinfunction "MGTAVTT")
			(pintype "passive")
		)
		(pad "C9" smd circle
			(at -2.5 -8.5 90)
			(size 0.5 0.5)
			(layers "F.Cu" "F.Mask" "F.Paste")
			(net 567 "unconnected-(U14E-MGTPRXN3_216-PadC9)")
			(pinfunction "MGTPRXN3_216")
			(pintype "bidirectional+no_connect")
		)
		(pad "C10" smd circle
			(at -1.5 -8.5 90)
			(size 0.5 0.5)
			(layers "F.Cu" "F.Mask" "F.Paste")
			(net 1 "GND")
			(pinfunction "GND")
			(pintype "passive")
		)
		(pad "C11" smd circle
			(at -0.5 -8.5 90)
			(size 0.5 0.5)
			(layers "F.Cu" "F.Mask" "F.Paste")
			(net 568 "unconnected-(U14E-MGTPRXN1_216-PadC11)")
			(pinfunction "MGTPRXN1_216")
			(pintype "bidirectional+no_connect")
		)
		(pad "C12" smd circle
			(at 0.498 -8.5 90)
			(size 0.5 0.5)
			(layers "F.Cu" "F.Mask" "F.Paste")
			(net 1 "GND")
			(pinfunction "GND")
			(pintype "passive")
		)
		(pad "C13" smd circle
			(at 1.499 -8.5 90)
			(size 0.5 0.5)
			(layers "F.Cu" "F.Mask" "F.Paste")
			(net 45 "I2C[8]_SCL")
			(pinfunction "IO_L8P_T1_16")
			(pintype "bidirectional")
		)
		(pad "C14" smd circle
			(at 2.499 -8.5 90)
			(size 0.5 0.5)
			(layers "F.Cu" "F.Mask" "F.Paste")
			(net 46 "I2C[8]_SDA")
			(pinfunction "IO_L3P_T0_DQS_16")
			(pintype "bidirectional")
		)
		(pad "C15" smd circle
			(at 3.499 -8.5 90)
			(size 0.5 0.5)
			(layers "F.Cu" "F.Mask" "F.Paste")
			(net 81 "NCSI_RXER")
			(pinfunction "IO_L3N_T0_DQS_16")
			(pintype "bidirectional")
		)
		(pad "C16" smd circle
			(at 4.498 -8.5 90)
			(size 0.5 0.5)
			(layers "F.Cu" "F.Mask" "F.Paste")
			(net 1 "GND")
			(pinfunction "GND")
			(pintype "passive")
		)
		(pad "C17" smd circle
			(at 5.499 -8.5 90)
			(size 0.5 0.5)
			(layers "F.Cu" "F.Mask" "F.Paste")
			(net 569 "unconnected-(U14B-IO_L12N_T1_MRCC_16-PadC17)")
			(pinfunction "IO_L12N_T1_MRCC_16")
			(pintype "bidirectional+no_connect")
		)
		(pad "C18" smd circle
			(at 6.499 -8.5 90)
			(size 0.5 0.5)
			(layers "F.Cu" "F.Mask" "F.Paste")
			(net 503 "/FPGA banks 13-16/GCLK100")
			(pinfunction "IO_L13P_T2_MRCC_16")
			(pintype "bidirectional")
		)
		(pad "C19" smd circle
			(at 7.499 -8.5 90)
			(size 0.5 0.5)
			(layers "F.Cu" "F.Mask" "F.Paste")
			(net 173 "I3C[2]_SCL_3V3")
			(pinfunction "IO_L13N_T2_MRCC_16")
			(pintype "bidirectional")
		)
		(pad "C20" smd circle
			(at 8.499 -8.5 90)
			(size 0.5 0.5)
			(layers "F.Cu" "F.Mask" "F.Paste")
			(net 560 "ROT_MOSI")
			(pinfunction "IO_L19N_T3_VREF_16")
			(pintype "bidirectional")
		)
		(pad "C21" smd circle
			(at 9.499 -8.5 90)
			(size 0.5 0.5)
			(layers "F.Cu" "F.Mask" "F.Paste")
			(net 2 "VCC3V3")
			(pinfunction "VCCO_16")
			(pintype "passive")
		)
		(pad "C22" smd circle
			(at 10.499 -8.5 90)
			(size 0.5 0.5)
			(layers "F.Cu" "F.Mask" "F.Paste")
			(net 559 "ROT_MISO")
			(pinfunction "IO_L20P_T3_16")
			(pintype "bidirectional")
		)
		(pad "D1" smd circle
			(at -10.5 -7.5 90)
			(size 0.5 0.5)
			(layers "F.Cu" "F.Mask" "F.Paste")
			(net 474 "DDR3_DQS1_N")
			(pinfunction "IO_L3N_T0_DQS_AD5N_35")
			(pintype "bidirectional")
		)
		(pad "D2" smd circle
			(at -9.5 -7.5 90)
			(size 0.5 0.5)
			(layers "F.Cu" "F.Mask" "F.Paste")
			(net 184 "DDR3_DQ11")
			(pinfunction "IO_L4N_T0_35")
			(pintype "bidirectional")
		)
		(pad "D3" smd circle
			(at -8.5 -7.5 90)
			(size 0.5 0.5)
			(layers "F.Cu" "F.Mask" "F.Paste")
			(net 1 "GND")
			(pinfunction "GND")
			(pintype "passive")
		)
		(pad "D4" smd circle
			(at -7.5 -7.5 90)
			(size 0.5 0.5)
			(layers "F.Cu" "F.Mask" "F.Paste")
			(net 1 "GND")
			(pinfunction "GND")
			(pintype "passive")
		)
		(pad "D5" smd circle
			(at -6.5 -7.5 90)
			(size 0.5 0.5)
			(layers "F.Cu" "F.Mask" "F.Paste")
			(net 570 "unconnected-(U14E-MGTPTXP1_216-PadD5)")
			(pinfunction "MGTPTXP1_216")
			(pintype "bidirectional+no_connect")
		)
		(pad "D6" smd circle
			(at -5.5 -7.5 90)
			(size 0.5 0.5)
			(layers "F.Cu" "F.Mask" "F.Paste")
			(net 6 "VCC1V0")
			(pinfunction "MGTAVCC")
			(pintype "power_in")
		)
		(pad "D7" smd circle
			(at -4.5 -7.5 90)
			(size 0.5 0.5)
			(layers "F.Cu" "F.Mask" "F.Paste")
			(net 571 "unconnected-(U14E-MGTPTXP3_216-PadD7)")
			(pinfunction "MGTPTXP3_216")
			(pintype "bidirectional+no_connect")
		)
		(pad "D8" smd circle
			(at -3.5 -7.5 90)
			(size 0.5 0.5)
			(layers "F.Cu" "F.Mask" "F.Paste")
			(net 1 "GND")
			(pinfunction "GND")
			(pintype "passive")
		)
		(pad "D9" smd circle
			(at -2.5 -7.5 90)
			(size 0.5 0.5)
			(layers "F.Cu" "F.Mask" "F.Paste")
			(net 572 "unconnected-(U14E-MGTPRXP3_216-PadD9)")
			(pinfunction "MGTPRXP3_216")
			(pintype "bidirectional+no_connect")
		)
		(pad "D10" smd circle
			(at -1.5 -7.5 90)
			(size 0.5 0.5)
			(layers "F.Cu" "F.Mask" "F.Paste")
			(net 6 "VCC1V0")
			(pinfunction "MGTAVCC")
			(pintype "passive")
		)
		(pad "D11" smd circle
			(at -0.5 -7.5 90)
			(size 0.5 0.5)
			(layers "F.Cu" "F.Mask" "F.Paste")
			(net 587 "unconnected-(U14E-MGTPRXP1_216-PadD11)")
			(pinfunction "MGTPRXP1_216")
			(pintype "bidirectional+no_connect")
		)
		(pad "D12" smd circle
			(at 0.498 -7.5 90)
			(size 0.5 0.5)
			(layers "F.Cu" "F.Mask" "F.Paste")
			(net 1 "GND")
			(pinfunction "GND")
			(pintype "passive")
		)
		(pad "D13" smd circle
			(at 1.499 -7.5 90)
			(size 0.5 0.5)
			(layers "F.Cu" "F.Mask" "F.Paste")
			(net 1 "GND")
			(pinfunction "GND")
			(pintype "passive")
		)
		(pad "D14" smd circle
			(at 2.499 -7.5 90)
			(size 0.5 0.5)
			(layers "F.Cu" "F.Mask" "F.Paste")
			(net 79 "NCSI_TXD0")
			(pinfunction "IO_L6P_T0_16")
			(pintype "bidirectional")
		)
		(pad "D15" smd circle
			(at 3.499 -7.5 90)
			(size 0.5 0.5)
			(layers "F.Cu" "F.Mask" "F.Paste")
			(net 588 "unconnected-(U14B-IO_L6N_T0_VREF_16-PadD15)")
			(pinfunction "IO_L6N_T0_VREF_16")
			(pintype "bidirectional+no_connect")
		)
		(pad "D16" smd circle
			(at 4.498 -7.5 90)
			(size 0.5 0.5)
			(layers "F.Cu" "F.Mask" "F.Paste")
			(net 525 "SPI0_CS_N_R")
			(pinfunction "IO_L5N_T0_16")
			(pintype "bidirectional")
		)
		(pad "D17" smd circle
			(at 5.499 -7.5 90)
			(size 0.5 0.5)
			(layers "F.Cu" "F.Mask" "F.Paste")
			(net 39 "UART0_SCM_RX")
			(pinfunction "IO_L12P_T1_MRCC_16")
			(pintype "bidirectional")
		)
		(pad "D18" smd circle
			(at 6.499 -7.5 90)
			(size 0.5 0.5)
			(layers "F.Cu" "F.Mask" "F.Paste")
			(net 2 "VCC3V3")
			(pinfunction "VCCO_16")
			(pintype "passive")
		)
		(pad "D19" smd circle
			(at 7.499 -7.5 90)
			(size 0.5 0.5)
			(layers "F.Cu" "F.Mask" "F.Paste")
			(net 175 "I3C[3]_SCL_3V3")
			(pinfunction "IO_L14N_T2_SRCC_16")
			(pintype "bidirectional")
		)
		(pad "D20" smd circle
			(at 8.499 -7.5 90)
			(size 0.5 0.5)
			(layers "F.Cu" "F.Mask" "F.Paste")
			(net 171 "I3C[1]_SCL_3V3")
			(pinfunction "IO_L19P_T3_16")
			(pintype "bidirectional")
		)
		(pad "D21" smd circle
			(at 9.499 -7.5 90)
			(size 0.5 0.5)
			(layers "F.Cu" "F.Mask" "F.Paste")
			(net 593 "unconnected-(U14B-IO_L23N_T3_16-PadD21)")
			(pinfunction "IO_L23N_T3_16")
			(pintype "bidirectional+no_connect")
		)
		(pad "D22" smd circle
			(at 10.499 -7.5 90)
			(size 0.5 0.5)
			(layers "F.Cu" "F.Mask" "F.Paste")
			(net 561 "ROT_SS")
			(pinfunction "IO_L22N_T3_16")
			(pintype "bidirectional")
		)
		(pad "E1" smd circle
			(at -10.5 -6.5 90)
			(size 0.5 0.5)
			(layers "F.Cu" "F.Mask" "F.Paste")
			(net 475 "DDR3_DQS1_P")
			(pinfunction "IO_L3P_T0_DQS_AD5P_35")
			(pintype "bidirectional")
		)
		(pad "E2" smd circle
			(at -9.5 -6.5 90)
			(size 0.5 0.5)
			(layers "F.Cu" "F.Mask" "F.Paste")
			(net 179 "DDR3_DQ14")
			(pinfunction "IO_L4P_T0_35")
			(pintype "bidirectional")
		)
		(pad "E3" smd circle
			(at -8.5 -6.5 90)
			(size 0.5 0.5)
			(layers "F.Cu" "F.Mask" "F.Paste")
			(net 193 "DDR3_DQ8")
			(pinfunction "IO_L6N_T0_VREF_35")
			(pintype "bidirectional")
		)
		(pad "E4" smd circle
			(at -7.5 -6.5 90)
			(size 0.5 0.5)
			(layers "F.Cu" "F.Mask" "F.Paste")
			(net 1 "GND")
			(pinfunction "GND")
			(pintype "passive")
		)
		(pad "E5" smd circle
			(at -6.5 -6.5 90)
			(size 0.5 0.5)
			(layers "F.Cu" "F.Mask" "F.Paste")
			(net 1 "GND")
			(pinfunction "GND")
			(pintype "passive")
		)
		(pad "E6" smd circle
			(at -5.5 -6.5 90)
			(size 0.5 0.5)
			(layers "F.Cu" "F.Mask" "F.Paste")
			(net 380 "PCIE_BMC_CLK_100_N")
			(pinfunction "MGTREFCLK0N_216")
			(pintype "bidirectional")
		)
		(pad "E7" smd circle
			(at -4.5 -6.5 90)
			(size 0.5 0.5)
			(layers "F.Cu" "F.Mask" "F.Paste")
			(net 1 "GND")
			(pinfunction "GND")
			(pintype "passive")
		)
		(pad "E8" smd circle
			(at -3.5 -6.5 90)
			(size 0.5 0.5)
			(layers "F.Cu" "F.Mask" "F.Paste")
			(net 6 "VCC1V0")
			(pinfunction "MGTAVCC")
			(pintype "passive")
		)
		(pad "E9" smd circle
			(at -2.5 -6.5 90)
			(size 0.5 0.5)
			(layers "F.Cu" "F.Mask" "F.Paste")
			(net 1 "GND")
			(pinfunction "GND")
			(pintype "passive")
		)
		(pad "E10" smd circle
			(at -1.5 -6.5 90)
			(size 0.5 0.5)
			(layers "F.Cu" "F.Mask" "F.Paste")
			(net 594 "unconnected-(U14E-MGTREFCLK1N_216-PadE10)")
			(pinfunction "MGTREFCLK1N_216")
			(pintype "bidirectional+no_connect")
		)
		(pad "E11" smd circle
			(at -0.5 -6.5 90)
			(size 0.5 0.5)
			(layers "F.Cu" "F.Mask" "F.Paste")
			(net 1 "GND")
			(pinfunction "GND")
			(pintype "passive")
		)
		(pad "E12" smd circle
			(at 0.498 -6.5 90)
			(size 0.5 0.5)
			(layers "F.Cu" "F.Mask" "F.Paste")
			(net 5 "VCC1V8")
			(pinfunction "VCCBATT")
			(pintype "power_in")
		)
		(pad "E13" smd circle
			(at 1.499 -6.5 90)
			(size 0.5 0.5)
			(layers "F.Cu" "F.Mask" "F.Paste")
			(net 24 "I2C[7]_SDA")
			(pinfunction "IO_L4P_T0_16")
			(pintype "bidirectional")
		)
		(pad "E14" smd circle
			(at 2.499 -6.5 90)
			(size 0.5 0.5)
			(layers "F.Cu" "F.Mask" "F.Paste")
			(net 80 "NCSI_TXD1")
			(pinfunction "IO_L4N_T0_16")
			(pintype "bidirectional")
		)
		(pad "E15" smd circle
			(at 3.499 -6.5 90)
			(size 0.5 0.5)
			(layers "F.Cu" "F.Mask" "F.Paste")
			(net 2 "VCC3V3")
			(pinfunction "VCCO_16")
			(pintype "passive")
		)
		(pad "E16" smd circle
			(at 4.498 -6.5 90)
			(size 0.5 0.5)
			(layers "F.Cu" "F.Mask" "F.Paste")
			(net 524 "SPI0_CLK_R")
			(pinfunction "IO_L5P_T0_16")
			(pintype "bidirectional")
		)
		(pad "E17" smd circle
			(at 5.499 -6.5 90)
			(size 0.5 0.5)
			(layers "F.Cu" "F.Mask" "F.Paste")
			(net 35 "UART0_SCM_TX")
			(pinfunction "IO_L2N_T0_16")
			(pintype "bidirectional")
		)
		(pad "E18" smd circle
			(at 6.499 -6.5 90)
			(size 0.5 0.5)
			(layers "F.Cu" "F.Mask" "F.Paste")
			(net 595 "unconnected-(U14B-IO_L15N_T2_DQS_16-PadE18)")
			(pinfunction "IO_L15N_T2_DQS_16")
			(pintype "bidirectional+no_connect")
		)
		(pad "E19" smd circle
			(at 7.499 -6.5 90)
			(size 0.5 0.5)
			(layers "F.Cu" "F.Mask" "F.Paste")
			(net 596 "unconnected-(U14B-IO_L14P_T2_SRCC_16-PadE19)")
			(pinfunction "IO_L14P_T2_SRCC_16")
			(pintype "bidirectional+no_connect")
		)
		(pad "E20" smd circle
			(at 8.499 -6.5 90)
			(size 0.5 0.5)
			(layers "F.Cu" "F.Mask" "F.Paste")
			(net 1 "GND")
			(pinfunction "GND")
			(pintype "passive")
		)
		(pad "E21" smd circle
			(at 9.499 -6.5 90)
			(size 0.5 0.5)
			(layers "F.Cu" "F.Mask" "F.Paste")
			(net 521 "PRSNT0_N_R")
			(pinfunction "IO_L23P_T3_16")
			(pintype "bidirectional")
		)
		(pad "E22" smd circle
			(at 10.499 -6.5 90)
			(size 0.5 0.5)
			(layers "F.Cu" "F.Mask" "F.Paste")
			(net 522 "VIRTUAL_RESEAT_R")
			(pinfunction "IO_L22P_T3_16")
			(pintype "bidirectional")
		)
		(pad "F1" smd circle
			(at -10.5 -5.5 90)
			(size 0.5 0.5)
			(layers "F.Cu" "F.Mask" "F.Paste")
			(net 181 "DDR3_DM1")
			(pinfunction "IO_L5N_T0_AD13N_35")
			(pintype "bidirectional")
		)
		(pad "F2" smd circle
			(at -9.5 -5.5 90)
			(size 0.5 0.5)
			(layers "F.Cu" "F.Mask" "F.Paste")
			(net 3 "VCC1V35")
			(pinfunction "VCCO_35")
			(pintype "passive")
		)
		(pad "F3" smd circle
			(at -8.5 -5.5 90)
			(size 0.5 0.5)
			(layers "F.Cu" "F.Mask" "F.Paste")
			(net 183 "DDR3_DQ10")
			(pinfunction "IO_L6P_T0_35")
			(pintype "bidirectional")
		)
	)
)
